# T6G (Grand Teton) — schematic netlist excerpt (pin names and nets, part order shuffled) for the footprints in the layout excerpt that follows; sources: Cadence DE-HDL packaged netlist, KiCad conversion of 04192023_DAF0TMB3IC0_F0TG_MB_C_brd_V02_OCP.brd

R6797  Q_RES  0 5% CHIP  pkg 0201LF  page 343 : A = NCF_CPU1_P2_GND ; B = GND
R35  Q_RES  10K 1% CHIP  pkg 0402LF  page 92 : A = PD_CHG_CPU0_DIMM0_SAA ; B = GND

Q87  MOSFET_NCH_DUAL  PJT138K IC  pkg SOT363XD  page 254
  S1  = GND
  G1  = RST_CPU0_RSMRST_N
  D2  = LED_PWRGD_SYS_PWROK_R_D
  S2  = GND
  G2  = SCM_SYS_PWROK_R2
  D1  = LED_RST_RSMRST_PLD_R_N_D

(kicad_pcb
	(version 20260206)
	(generator "pcbnew")
	(generator_version "10.0")
	(general
		(thickness 1.6)
		(legacy_teardrops no)
	)
	(paper "A4")
	(title_block
		(title "04192023_DAF0TMB3IC0_F0TG_MB_C_brd_V02_OCP.brd")
		(comment 1 "Grand Teton / footprints 7916-7918 of 8354")
	)
	(layers
		(0 "F.Cu" signal "TOP")
		(4 "In1.Cu" signal "GND")
		(6 "In2.Cu" signal "IN1")
		(8 "In3.Cu" signal "GND1")
		(10 "In4.Cu" signal "IN2")
		(12 "In5.Cu" signal "GND2")
		(14 "In6.Cu" signal "IN3")
		(16 "In7.Cu" signal "GND3")
		(18 "In8.Cu" signal "VCC")
		(20 "In9.Cu" signal "VCC1")
		(22 "In10.Cu" signal "GND4")
		(24 "In11.Cu" signal "IN4")
		(26 "In12.Cu" signal "GND5")
		(28 "In13.Cu" signal "IN5")
		(30 "In14.Cu" signal "GND6")
		(32 "In15.Cu" signal "IN6")
		(34 "In16.Cu" signal "GND7")
		(2 "B.Cu" signal "BOTTOM")
		(9 "F.Adhes" user "F.Adhesive")
		(11 "B.Adhes" user "B.Adhesive")
		(13 "F.Paste" user "Package Geometry/Pastemask Top")
		(15 "B.Paste" user "Package Geometry/Pastemask Bottom")
		(5 "F.SilkS" user "Ref Des/Silkscreen Top")
		(7 "B.SilkS" user "Ref Des/Silkscreen Bottom")
		(1 "F.Mask" user "Board Geometry/Soldermask Top")
		(3 "B.Mask" user "Board Geometry/Soldermask Bottom")
		(17 "Dwgs.User" user "User.Drawings")
		(19 "Cmts.User" user "User.Comments")
		(21 "Eco1.User" user "User.Eco1")
		(23 "Eco2.User" user "User.Eco2")
		(25 "Edge.Cuts" user "Board Geometry/Outline")
		(27 "Margin" user)
		(31 "F.CrtYd" user "Package Geometry/Place Bound Top")
		(29 "B.CrtYd" user "Package Geometry/Place Bound Bottom")
		(35 "F.Fab" user "Ref Des/Assembly Top")
		(33 "B.Fab" user "Ref Des/Assembly Bottom")
	)
	(footprint ""
		(layer "B.Cu")
		(at 168.783762 -383.304288 180)
		(property "Reference" "R6797"
			(at 0 0 0)
			(layer "B.SilkS")
			(hide yes)
			(effects
				(font
					(size 1.27 1.27)
				)
				(justify mirror)
			)
		)
		(property "Value" ""
			(at 0 0 0)
			(layer "B.Fab")
			(effects
				(font
					(size 1.27 1.27)
				)
				(justify mirror)
			)
		)
		(duplicate_pad_numbers_are_jumpers no)
		(fp_line
			(start 0.32512 0.175006)
			(end 0.32512 -0.175006)
			(stroke
				(width 0.1)
				(type default)
			)
			(layer "B.Fab")
		)
		(fp_line
			(start 0.32512 -0.175006)
			(end -0.32512 -0.175006)
			(stroke
				(width 0.1)
				(type default)
			)
			(layer "B.Fab")
		)
		(fp_line
			(start -0.32512 0.175006)
			(end 0.32512 0.175006)
			(stroke
				(width 0.1)
				(type default)
			)
			(layer "B.Fab")
		)
		(fp_line
			(start -0.32512 -0.175006)
			(end -0.32512 0.175006)
			(stroke
				(width 0.1)
				(type default)
			)
			(layer "B.Fab")
		)
		(pad "1" smd rect
			(at 0.2667 0)
			(size 0.3048 0.381)
			(layers "B.Cu" "B.Mask" "B.Paste")
			(net "NCF_CPU1_P2_GND")
		)
		(pad "2" smd rect
			(at -0.2667 0 180)
			(size 0.3048 0.381)
			(layers "B.Cu" "B.Mask" "B.Paste")
			(net "GND")
		)
	)
	(footprint ""
		(layer "B.Cu")
		(at 413.123634 -194.88531 180)
		(property "Reference" "R35"
			(at 0 0 0)
			(layer "B.SilkS")
			(hide yes)
			(effects
				(font
					(size 1.27 1.27)
				)
				(justify mirror)
			)
		)
		(property "Value" ""
			(at 0 0 0)
			(layer "B.Fab")
			(effects
				(font
					(size 1.27 1.27)
				)
				(justify mirror)
			)
		)
		(duplicate_pad_numbers_are_jumpers no)
		(fp_line
			(start 0.7874 0.4064)
			(end 0.7874 -0.4064)
			(stroke
				(width 0.1524)
				(type default)
			)
			(layer "B.SilkS")
		)
		(fp_line
			(start 0.7874 -0.4064)
			(end -0.7874 -0.4064)
			(stroke
				(width 0.1524)
				(type default)
			)
			(layer "B.SilkS")
		)
		(fp_line
			(start -0.7874 0.4064)
			(end 0.7874 0.4064)
			(stroke
				(width 0.1524)
				(type default)
			)
			(layer "B.SilkS")
		)
		(fp_line
			(start -0.7874 -0.4064)
			(end -0.7874 0.4064)
			(stroke
				(width 0.1524)
				(type default)
			)
			(layer "B.SilkS")
		)
		(fp_line
			(start 0.67945 0.3048)
			(end 0.67945 -0.305054)
			(stroke
				(width 0.1)
				(type default)
			)
			(layer "B.Fab")
		)
		(fp_line
			(start 0.67945 -0.305054)
			(end 0.12065 -0.305054)
			(stroke
				(width 0.1)
				(type default)
			)
			(layer "B.Fab")
		)
		(fp_line
			(start 0.12065 0.3048)
			(end 0.67945 0.3048)
			(stroke
				(width 0.1)
				(type default)
			)
			(layer "B.Fab")
		)
		(fp_line
			(start 0.12065 0.2794)
			(end 0.12065 0.3048)
			(stroke
				(width 0.1)
				(type default)
			)
			(layer "B.Fab")
		)
		(fp_line
			(start 0.12065 -0.2794)
			(end -0.12065 -0.2794)
			(stroke
				(width 0.1)
				(type default)
			)
			(layer "B.Fab")
		)
		(fp_line
			(start 0.12065 -0.305054)
			(end 0.12065 -0.2794)
			(stroke
				(width 0.1)
				(type default)
			)
			(layer "B.Fab")
		)
		(fp_line
			(start -0.120396 0.3048)
			(end -0.120396 0.2794)
			(stroke
				(width 0.1)
				(type default)
			)
			(layer "B.Fab")
		)
		(fp_line
			(start -0.120396 0.2794)
			(end 0.12065 0.2794)
			(stroke
				(width 0.1)
				(type default)
			)
			(layer "B.Fab")
		)
		(fp_line
			(start -0.12065 -0.2794)
			(end -0.12065 -0.3048)
			(stroke
				(width 0.1)
				(type default)
			)
			(layer "B.Fab")
		)
		(fp_line
			(start -0.12065 -0.3048)
			(end -0.67945 -0.3048)
			(stroke
				(width 0.1)
				(type default)
			)
			(layer "B.Fab")
		)
		(fp_line
			(start -0.67945 0.3048)
			(end -0.120396 0.3048)
			(stroke
				(width 0.1)
				(type default)
			)
			(layer "B.Fab")
		)
		(fp_line
			(start -0.67945 -0.3048)
			(end -0.67945 0.3048)
			(stroke
				(width 0.1)
				(type default)
			)
			(layer "B.Fab")
		)
		(pad "1" smd circle
			(at 0.40005 0)
			(size 0 0)
			(layers "B.Cu" "B.Mask" "B.Paste")
			(net "PD_CHG_CPU0_DIMM0_SAA")
		)
		(pad "2" smd circle
			(at -0.40005 0)
			(size 0 0)
			(layers "B.Cu" "B.Mask" "B.Paste")
			(net "GND")
		)
	)
	(footprint ""
		(layer "B.Cu")
		(at 312.144664 -73.534778)
		(property "Reference" "Q87"
			(at 1.157478 2.63525 0)
			(unlocked yes)
			(layer "B.SilkS")
			(effects
				(font
					(size 0.7874 0.5842)
					(thickness 0.1524)
				)
				(justify left mirror)
			)
		)
		(property "Value" ""
			(at 0 0 0)
			(layer "B.Fab")
			(effects
				(font
					(size 1.27 1.27)
				)
				(justify mirror)
			)
		)
		(duplicate_pad_numbers_are_jumpers no)
		(fp_line
			(start -1.332738 -1.100074)
			(end -1.332738 1.100074)
			(stroke
				(width 0.1524)
				(type default)
			)
			(layer "B.SilkS")
		)
		(fp_line
			(start -1.332738 1.100074)
			(end 1.332738 1.100074)
			(stroke
				(width 0.1524)
				(type default)
			)
			(layer "B.SilkS")
		)
		(fp_line
			(start -0.4826 -1.100074)
			(end -1.332738 -1.100074)
			(stroke
				(width 0.1524)
				(type default)
			)
			(layer "B.SilkS")
		)
		(fp_line
			(start 0 -0.541274)
			(end -0.4826 -1.100074)
			(stroke
				(width 0.1524)
				(type default)
			)
			(layer "B.SilkS")
		)
		(fp_line
			(start 0.4826 -1.100074)
			(end 0 -0.541274)
			(stroke
				(width 0.1524)
				(type default)
			)
			(layer "B.SilkS")
		)
		(fp_line
			(start 1.332738 -1.100074)
			(end 0.4826 -1.100074)
			(stroke
				(width 0.1524)
				(type default)
			)
			(layer "B.SilkS")
		)
		(fp_line
			(start 1.332738 1.100074)
			(end 1.332738 -1.100074)
			(stroke
				(width 0.1524)
				(type default)
			)
			(layer "B.SilkS")
		)
		(fp_poly
			(pts
				(xy 1.533144 -0.649986) (xy 2.2352 -1.001014) (xy 2.2352 -0.298958)
			)
			(stroke
				(width 0)
				(type default)
			)
			(fill yes)
			(layer "B.SilkS")
		)
		(fp_line
			(start -0.674878 -1.100074)
			(end -0.674878 1.100074)
			(stroke
				(width 0.1)
				(type default)
			)
			(layer "B.Fab")
		)
		(fp_line
			(start -0.674878 1.100074)
			(end 0.674878 1.100074)
			(stroke
				(width 0.1)
				(type default)
			)
			(layer "B.Fab")
		)
		(fp_line
			(start 0.674878 -1.100074)
			(end -0.674878 -1.100074)
			(stroke
				(width 0.1)
				(type default)
			)
			(layer "B.Fab")
		)
		(fp_line
			(start 0.674878 1.100074)
			(end 0.674878 -1.100074)
			(stroke
				(width 0.1)
				(type default)
			)
			(layer "B.Fab")
		)
		(fp_poly
			(pts
				(xy 2.2352 -0.298958) (xy 2.2352 -1.001014) (xy 1.533144 -0.649986)
			)
			(stroke
				(width 0)
				(type default)
			)
			(fill yes)
			(layer "B.Fab")
		)
		(pad "1" smd rect
			(at 0.94996 -0.649986 90)
			(size 0.4318 0.508)
			(layers "B.Cu" "B.Mask" "B.Paste")
			(net "GND")
		)
		(pad "2" smd rect
			(at 0.94996 0 90)
			(size 0.4318 0.508)
			(layers "B.Cu" "B.Mask" "B.Paste")
			(net "RST_CPU0_RSMRST_N")
		)
		(pad "3" smd rect
			(at 0.94996 0.649986 90)
			(size 0.4318 0.508)
			(layers "B.Cu" "B.Mask" "B.Paste")
			(net "LED_PWRGD_SYS_PWROK_R_D")
		)
		(pad "4" smd rect
			(at -0.94996 0.649986 90)
			(size 0.4318 0.508)
			(layers "B.Cu" "B.Mask" "B.Paste")
			(net "GND")
		)
		(pad "5" smd rect
			(at -0.94996 0 90)
			(size 0.4318 0.508)
			(layers "B.Cu" "B.Mask" "B.Paste")
			(net "SCM_SYS_PWROK_R2")
		)
		(pad "6" smd rect
			(at -0.94996 -0.649986 90)
			(size 0.4318 0.508)
			(layers "B.Cu" "B.Mask" "B.Paste")
			(net "LED_RST_RSMRST_PLD_R_N_D")
		)
	)
)
